# BASEBOARD_FAB2 (Tioga Pass) — schematic netlist excerpt (pin names and nets, part order shuffled) for the footprints in the layout excerpt that follows; sources: Cadence DE-HDL packaged netlist, KiCad conversion of Wiwynn_Tioga_Pass_MB.brd

J6L1  SCONN288_H44441003  SCONN  pkg PIP  page 54
  \12v\(1)  = P12V_NVDIMM_DEF
  VSS(93)  = GND
  DQ(4)  = M_F_DQ<4>
  VSS(92)  = GND
  DQ(0)  = M_F_DQ<0>
  VSS(91)  = GND
  DQS9P  = M_F_DQS_DP<9>
  DQS9N  = M_F_DQS_DN<9>
  VSS(90)  = GND
  DQ(6)  = M_F_DQ<6>
  VSS(89)  = GND
  DQ(2)  = M_F_DQ<2>
  VSS(88)  = GND
  DQ(12)  = M_F_DQ<12>
  VSS(87)  = GND
  DQ(8)  = M_F_DQ<8>
  VSS(86)  = GND
  DQS10P  = M_F_DQS_DP<10>
  DQS10N  = M_F_DQS_DN<10>
  VSS(85)  = GND
  DQ(14)  = M_F_DQ<14>
  VSS(84)  = GND
  DQ(10)  = M_F_DQ<10>
  VSS(83)  = GND
  DQ(20)  = M_F_DQ<20>
  VSS(82)  = GND
  DQ(16)  = M_F_DQ<16>
  VSS(81)  = GND
  DQS11P  = M_F_DQS_DP<11>
  DQS11N  = M_F_DQS_DN<11>
  VSS(80)  = GND
  DQ(22)  = M_F_DQ<22>
  VSS(79)  = GND
  DQ(18)  = M_F_DQ<18>
  VSS(78)  = GND
  DQ(28)  = M_F_DQ<28>
  VSS(77)  = GND
  DQ(24)  = M_F_DQ<24>
  VSS(76)  = GND
  DQS12P  = M_F_DQS_DP<12>
  DQS12N  = M_F_DQS_DN<12>
  VSS(75)  = GND
  DQ(30)  = M_F_DQ<30>
  VSS(74)  = GND
  DQ(26)  = M_F_DQ<26>
  VSS(73)  = GND
  CB(4)  = M_F_ECC<4>
  VSS(72)  = GND
  CB(0)  = M_F_ECC<0>
  VSS(71)  = GND
  DQS17P  = M_F_DQS_DP<17>
  DQS17N  = M_F_DQS_DN<17>
  VSS(70)  = GND
  CB(6)  = M_F_ECC<6>
  VSS(69)  = GND
  CB(2)  = M_F_ECC<2>
  VSS(68)  = GND
  RESET_N  = M_DEF_RST_N
  VDD(25)  = PVDDQ_DEF
  CKE(0)  = M_F_CKE<2>
  VDD(24)  = PVDDQ_DEF
  ACT_N  = M_F_ACT_N
  BG(0)  = M_F_BG<0>
  VDD(23)  = PVDDQ_DEF
  A12  = M_F_MA<12>
  A9  = M_F_MA<9>
  VDD(22)  = PVDDQ_DEF
  A8  = M_F_MA<8>
  A6  = M_F_MA<6>
  VDD(21)  = PVDDQ_DEF
  A3  = M_F_MA<3>
  A1  = M_F_MA<1>
  VDD(20)  = PVDDQ_DEF
  CK0P  = M_F_CLK_DP<2>
  CK0N  = M_F_CLK_DN<2>
  VDD(19)  = PVDDQ_DEF
  VTT(1)  = PVTT_DEF
  EVENT_N  = FM_DIMM_EVENT_COD_N
  A0  = M_F_MA<0>
  VDD(18)  = PVDDQ_DEF
  BA(0)  = M_F_BA<0>
  A16_RAS_N  = M_F_MA<16>
  VDD(17)  = PVDDQ_DEF
  S0_N  = M_F_CS_N<4>
  VDD(16)  = PVDDQ_DEF
  A15_CAS_N  = M_F_MA<15>
  ODT(0)  = M_F_ODT<2>
  VDD(15)  = PVDDQ_DEF
  S1_N  = M_F_CS_N<5>
  VDD(14)  = PVDDQ_DEF
  ODT(1)  = M_F_ODT<3>
  VDD(13)  = PVDDQ_DEF
  S2_N_C(0)  = M_F_CS_N<6>
  VSS(67)  = GND
  DQ(36)  = M_F_DQ<36>
  VSS(66)  = GND
  DQ(32)  = M_F_DQ<32>
  VSS(65)  = GND
  DQS13P  = M_F_DQS_DP<13>
  DQS13N  = M_F_DQS_DN<13>
  VSS(64)  = GND
  DQ(38)  = M_F_DQ<38>
  VSS(63)  = GND
  DQ(34)  = M_F_DQ<34>
  VSS(62)  = GND
  DQ(44)  = M_F_DQ<44>
  VSS(61)  = GND
  DQ(40)  = M_F_DQ<40>
  VSS(60)  = GND
  DQS14P  = M_F_DQS_DP<14>
  DQS14N  = M_F_DQS_DN<14>
  VSS(59)  = GND
  DQ(46)  = M_F_DQ<46>
  VSS(58)  = GND
  DQ(42)  = M_F_DQ<42>
  VSS(57)  = GND
  DQ(52)  = M_F_DQ<52>
  VSS(56)  = GND
  DQ(48)  = M_F_DQ<48>
  VSS(55)  = GND
  DQS15P  = M_F_DQS_DP<15>
  DQS15N  = M_F_DQS_DN<15>
  VSS(54)  = GND
  DQ(54)  = M_F_DQ<54>
  VSS(53)  = GND
  DQ(50)  = M_F_DQ<50>
  VSS(52)  = GND
  DQ(60)  = M_F_DQ<60>
  VSS(51)  = GND
  DQ(56)  = M_F_DQ<56>
  VSS(50)  = GND
  DQS16P  = M_F_DQS_DP<16>
  DQS16N  = M_F_DQS_DN<16>
  VSS(49)  = GND
  DQ(62)  = M_F_DQ<62>
  VSS(48)  = GND
  DQ(58)  = M_F_DQ<58>
  VSS(47)  = GND
  SA(0)  = PVPP_DEF
  SA(1)  = GND
  SCL  = SMB_DDR_DEF_VPP_SCL
  VPP(4)  = PVPP_DEF
  VPP(3)  = PVPP_DEF
  RFU(2)  = TP_CH_F_DIMM_F1_RFU_2
  \12v\(0)  = P12V_NVDIMM_DEF
  VREFCA  = M_F_VREF
  VSS(46)  = GND
  DQ(5)  = M_F_DQ<5>
  VSS(45)  = GND
  DQ(1)  = M_F_DQ<1>
  VSS(44)  = GND
  DQS0N  = M_F_DQS_DN<0>
  DQS0P  = M_F_DQS_DP<0>
  VSS(43)  = GND
  DQ(7)  = M_F_DQ<7>
  VSS(42)  = GND
  DQ(3)  = M_F_DQ<3>
  VSS(41)  = GND
  DQ(13)  = M_F_DQ<13>
  VSS(40)  = GND
  DQ(9)  = M_F_DQ<9>
  VSS(39)  = GND
  DQS1N  = M_F_DQS_DN<1>
  DQS1P  = M_F_DQS_DP<1>
  VSS(38)  = GND
  DQ(15)  = M_F_DQ<15>
  VSS(37)  = GND
  DQ(11)  = M_F_DQ<11>
  VSS(36)  = GND
  DQ(21)  = M_F_DQ<21>
  VSS(35)  = GND
  DQ(17)  = M_F_DQ<17>
  VSS(34)  = GND
  DQS2N  = M_F_DQS_DN<2>
  DQS2P  = M_F_DQS_DP<2>
  VSS(33)  = GND
  DQ(23)  = M_F_DQ<23>
  VSS(32)  = GND
  DQ(19)  = M_F_DQ<19>
  VSS(31)  = GND
  DQ(29)  = M_F_DQ<29>
  VSS(30)  = GND
  DQ(25)  = M_F_DQ<25>
  VSS(29)  = GND
  DQS3N  = M_F_DQS_DN<3>
  DQS3P  = M_F_DQS_DP<3>
  VSS(28)  = GND
  DQ(31)  = M_F_DQ<31>
  VSS(27)  = GND
  DQ(27)  = M_F_DQ<27>
  VSS(26)  = GND
  CB(5)  = M_F_ECC<5>
  VSS(25)  = GND
  CB(1)  = M_F_ECC<1>
  VSS(24)  = GND
  DQS8N  = M_F_DQS_DN<8>
  DQS8P  = M_F_DQS_DP<8>
  VSS(23)  = GND
  CB(7)  = M_F_ECC<7>
  VSS(22)  = GND
  CB(3)  = M_F_ECC<3>
  VSS(21)  = GND
  CKE(1)  = M_F_CKE<3>
  VDD(12)  = PVDDQ_DEF
  RFU(0)  = TP_CH_F_DIMM_F1_RFU_0
  VDD(11)  = PVDDQ_DEF
  BG(1)  = M_F_BG<1>
  ALERT_N  = M_F_ALERT_N
  VDD(10)  = PVDDQ_DEF
  A11  = M_F_MA<11>
  A7  = M_F_MA<7>
  VDD(9)  = PVDDQ_DEF
  A5  = M_F_MA<5>
  A4  = M_F_MA<4>
  VDD(8)  = PVDDQ_DEF
  A2  = M_F_MA<2>
  VDD(7)  = PVDDQ_DEF
  CK1P  = M_F_CLK_DP<3>
  CK1N  = M_F_CLK_DN<3>
  VDD(6)  = PVDDQ_DEF
  VTT(0)  = PVTT_DEF
  PAR  = M_F_PAR
  VDD(5)  = PVDDQ_DEF
  BA(1)  = M_F_BA<1>
  A10  = M_F_MA<10>
  VDD(4)  = PVDDQ_DEF
  RFU(1)  = TP_CH_F_DIMM_F1_RFU_1
  A14_WE_N  = M_F_MA<14>
  VDD(3)  = PVDDQ_DEF
  SAVE_N_NC  = FM_ADR_COMPLETE_DEF_N
  VDD(2)  = PVDDQ_DEF
  A13  = M_F_MA<13>
  VDD(1)  = PVDDQ_DEF
  A17  = M_F_MA<17>
  C(2)  = M_F_C<2>
  VDD(0)  = PVDDQ_DEF
  S3_N_C(1)  = M_F_CS_N<7>
  SA(2)  = PVPP_DEF
  VSS(20)  = GND
  DQ(37)  = M_F_DQ<37>
  VSS(19)  = GND
  DQ(33)  = M_F_DQ<33>
  VSS(18)  = GND
  DQS4N  = M_F_DQS_DN<4>
  DQS4P  = M_F_DQS_DP<4>
  VSS(17)  = GND
  DQ(39)  = M_F_DQ<39>
  VSS(16)  = GND
  DQ(35)  = M_F_DQ<35>
  VSS(15)  = GND
  DQ(45)  = M_F_DQ<45>
  VSS(14)  = GND
  DQ(41)  = M_F_DQ<41>
  VSS(13)  = GND
  DQS5N  = M_F_DQS_DN<5>
  DQS5P  = M_F_DQS_DP<5>
  VSS(12)  = GND
  DQ(47)  = M_F_DQ<47>
  VSS(11)  = GND
  DQ(43)  = M_F_DQ<43>
  VSS(10)  = GND
  DQ(53)  = M_F_DQ<53>
  VSS(9)  = GND
  DQ(49)  = M_F_DQ<49>
  VSS(8)  = GND
  DQS6N  = M_F_DQS_DN<6>
  DQS6P  = M_F_DQS_DP<6>
  VSS(7)  = GND
  DQ(55)  = M_F_DQ<55>
  VSS(6)  = GND
  DQ(51)  = M_F_DQ<51>
  VSS(5)  = GND
  DQ(61)  = M_F_DQ<61>
  VSS(4)  = GND
  DQ(57)  = M_F_DQ<57>
  VSS(3)  = GND
  DQS7N  = M_F_DQS_DN<7>
  DQS7P  = M_F_DQS_DP<7>
  VSS(2)  = GND
  DQ(63)  = M_F_DQ<63>
  VSS(1)  = GND
  DQ(59)  = M_F_DQ<59>
  VSS(0)  = GND
  VDDSPD  = PVPP_DEF
  SDA  = SMB_DDR_DEF_VPP_SDA
  VPP(1)  = PVPP_DEF
  VPP(0)  = PVPP_DEF
  VPP(2)  = PVPP_DEF

(kicad_pcb
	(version 20260206)
	(generator "pcbnew")
	(generator_version "10.0")
	(general
		(thickness 1.6)
		(legacy_teardrops no)
	)
	(paper "A4")
	(title_block
		(title "Wiwynn_Tioga_Pass_MB.brd")
		(comment 1 "Tioga Pass / footprint 4129 of 4770 (J6L1), pads 51-100 of 291")
	)
	(layers
		(0 "F.Cu" signal "TOP")
		(4 "In1.Cu" signal "L2GND")
		(6 "In2.Cu" signal "L3")
		(8 "In3.Cu" signal "L4GND")
		(10 "In4.Cu" signal "L5")
		(12 "In5.Cu" signal "L6GND")
		(14 "In6.Cu" signal "L7VCC")
		(16 "In7.Cu" signal "L8VCC")
		(18 "In8.Cu" signal "L9GND")
		(20 "In9.Cu" signal "L10")
		(22 "In10.Cu" signal "L11GND")
		(24 "In11.Cu" signal "L12")
		(26 "In12.Cu" signal "L13GND")
		(2 "B.Cu" signal "BOTTOM")
		(9 "F.Adhes" user "F.Adhesive")
		(11 "B.Adhes" user "B.Adhesive")
		(13 "F.Paste" user "Package Geometry/Pastemask Top")
		(15 "B.Paste" user "Package Geometry/Pastemask Bottom")
		(5 "F.SilkS" user "Ref Des/Silkscreen Top")
		(7 "B.SilkS" user "Ref Des/Silkscreen Bottom")
		(1 "F.Mask" user "Board Geometry/Soldermask Top")
		(3 "B.Mask" user "Board Geometry/Soldermask Bottom")
		(17 "Dwgs.User" user "User.Drawings")
		(19 "Cmts.User" user "User.Comments")
		(21 "Eco1.User" user "User.Eco1")
		(23 "Eco2.User" user "User.Eco2")
		(25 "Edge.Cuts" user "Board Geometry/Outline")
		(27 "Margin" user)
		(31 "F.CrtYd" user "Package Geometry/Place Bound Top")
		(29 "B.CrtYd" user "Package Geometry/Place Bound Bottom")
		(35 "F.Fab" user "Ref Des/Assembly Top")
		(33 "B.Fab" user "Ref Des/Assembly Bottom")
	)
	(footprint ""
		(layer "B.Cu")
		(at 194.700398 -152.078436 90)
		(property "Reference" "J6L1"
			(at 2.200148 37.96411 0)
			(unlocked yes)
			(layer "B.SilkS")
			(effects
				(font
					(size 0.7874 0.5842)
					(thickness 0.1524)
				)
				(justify left mirror)
			)
		)
		(property "Value" ""
			(at 0 0 90)
			(layer "B.Fab")
			(effects
				(font
					(size 1.27 1.27)
				)
				(justify mirror)
			)
		)
		(duplicate_pad_numbers_are_jumpers no)
		(pad "48" smd rect
			(at 0 39.949882 270)
			(size 1.8034 0.508)
			(layers "B.Cu" "B.Mask" "B.Paste")
			(net "GND")
		)
		(pad "49" smd rect
			(at 0 40.80002 270)
			(size 1.8034 0.508)
			(layers "B.Cu" "B.Mask" "B.Paste")
			(net "M_F_ECC<0>")
		)
		(pad "50" smd rect
			(at 0 41.649904 270)
			(size 1.8034 0.508)
			(layers "B.Cu" "B.Mask" "B.Paste")
			(net "GND")
		)
		(pad "51" smd rect
			(at 0 42.500042 270)
			(size 1.8034 0.508)
			(layers "B.Cu" "B.Mask" "B.Paste")
			(net "M_F_DQS_DP<17>")
		)
		(pad "52" smd rect
			(at 0 43.349926 270)
			(size 1.8034 0.508)
			(layers "B.Cu" "B.Mask" "B.Paste")
			(net "M_F_DQS_DN<17>")
		)
		(pad "53" smd rect
			(at 0 44.200064 270)
			(size 1.8034 0.508)
			(layers "B.Cu" "B.Mask" "B.Paste")
			(net "GND")
		)
		(pad "54" smd rect
			(at 0 45.049948 270)
			(size 1.8034 0.508)
			(layers "B.Cu" "B.Mask" "B.Paste")
			(net "M_F_ECC<6>")
		)
		(pad "55" smd rect
			(at 0 45.900086 270)
			(size 1.8034 0.508)
			(layers "B.Cu" "B.Mask" "B.Paste")
			(net "GND")
		)
		(pad "56" smd rect
			(at 0 46.74997 270)
			(size 1.8034 0.508)
			(layers "B.Cu" "B.Mask" "B.Paste")
			(net "M_F_ECC<2>")
		)
		(pad "57" smd rect
			(at 0 47.600108 270)
			(size 1.8034 0.508)
			(layers "B.Cu" "B.Mask" "B.Paste")
			(net "GND")
		)
		(pad "58" smd rect
			(at 0 48.449992 270)
			(size 1.8034 0.508)
			(layers "B.Cu" "B.Mask" "B.Paste")
			(net "M_DEF_RST_N")
		)
		(pad "59" smd rect
			(at 0 49.299876 270)
			(size 1.8034 0.508)
			(layers "B.Cu" "B.Mask" "B.Paste")
			(net "PVDDQ_DEF")
		)
		(pad "60" smd rect
			(at 0 50.150014 270)
			(size 1.8034 0.508)
			(layers "B.Cu" "B.Mask" "B.Paste")
			(net "M_F_CKE<2>")
		)
		(pad "61" smd rect
			(at 0 50.999898 270)
			(size 1.8034 0.508)
			(layers "B.Cu" "B.Mask" "B.Paste")
			(net "PVDDQ_DEF")
		)
		(pad "62" smd rect
			(at 0 51.850036 270)
			(size 1.8034 0.508)
			(layers "B.Cu" "B.Mask" "B.Paste")
			(net "M_F_ACT_N")
		)
		(pad "63" smd rect
			(at 0 52.69992 270)
			(size 1.8034 0.508)
			(layers "B.Cu" "B.Mask" "B.Paste")
			(net "M_F_BG<0>")
		)
		(pad "64" smd rect
			(at 0 53.550058 270)
			(size 1.8034 0.508)
			(layers "B.Cu" "B.Mask" "B.Paste")
			(net "PVDDQ_DEF")
		)
		(pad "65" smd rect
			(at 0 54.399942 270)
			(size 1.8034 0.508)
			(layers "B.Cu" "B.Mask" "B.Paste")
			(net "M_F_MA<12>")
		)
		(pad "66" smd rect
			(at 0 55.25008 270)
			(size 1.8034 0.508)
			(layers "B.Cu" "B.Mask" "B.Paste")
			(net "M_F_MA<9>")
		)
		(pad "67" smd rect
			(at 0 56.099964 270)
			(size 1.8034 0.508)
			(layers "B.Cu" "B.Mask" "B.Paste")
			(net "PVDDQ_DEF")
		)
		(pad "68" smd rect
			(at 0 56.950102 270)
			(size 1.8034 0.508)
			(layers "B.Cu" "B.Mask" "B.Paste")
			(net "M_F_MA<8>")
		)
		(pad "69" smd rect
			(at 0 57.799986 270)
			(size 1.8034 0.508)
			(layers "B.Cu" "B.Mask" "B.Paste")
			(net "M_F_MA<6>")
		)
		(pad "70" smd rect
			(at 0 58.650124 270)
			(size 1.8034 0.508)
			(layers "B.Cu" "B.Mask" "B.Paste")
			(net "PVDDQ_DEF")
		)
		(pad "71" smd rect
			(at 0 59.500008 270)
			(size 1.8034 0.508)
			(layers "B.Cu" "B.Mask" "B.Paste")
			(net "M_F_MA<3>")
		)
		(pad "72" smd rect
			(at 0 60.349892 270)
			(size 1.8034 0.508)
			(layers "B.Cu" "B.Mask" "B.Paste")
			(net "M_F_MA<1>")
		)
		(pad "73" smd rect
			(at 0 61.20003 270)
			(size 1.8034 0.508)
			(layers "B.Cu" "B.Mask" "B.Paste")
			(net "PVDDQ_DEF")
		)
		(pad "74" smd rect
			(at 0 62.049914 270)
			(size 1.8034 0.508)
			(layers "B.Cu" "B.Mask" "B.Paste")
			(net "M_F_CLK_DP<2>")
		)
		(pad "75" smd rect
			(at 0 62.900052 270)
			(size 1.8034 0.508)
			(layers "B.Cu" "B.Mask" "B.Paste")
			(net "M_F_CLK_DN<2>")
		)
		(pad "76" smd rect
			(at 0 63.749936 270)
			(size 1.8034 0.508)
			(layers "B.Cu" "B.Mask" "B.Paste")
			(net "PVDDQ_DEF")
		)
		(pad "77" smd rect
			(at 0 64.600074 270)
			(size 1.8034 0.508)
			(layers "B.Cu" "B.Mask" "B.Paste")
			(net "PVTT_DEF")
		)
		(pad "78" smd rect
			(at 0 70.550024 270)
			(size 1.8034 0.508)
			(layers "B.Cu" "B.Mask" "B.Paste")
			(net "FM_DIMM_EVENT_COD_N")
		)
		(pad "79" smd rect
			(at 0 71.399908 270)
			(size 1.8034 0.508)
			(layers "B.Cu" "B.Mask" "B.Paste")
			(net "M_F_MA<0>")
		)
		(pad "80" smd rect
			(at 0 72.250046 270)
			(size 1.8034 0.508)
			(layers "B.Cu" "B.Mask" "B.Paste")
			(net "PVDDQ_DEF")
		)
		(pad "81" smd rect
			(at 0 73.09993 270)
			(size 1.8034 0.508)
			(layers "B.Cu" "B.Mask" "B.Paste")
			(net "M_F_BA<0>")
		)
		(pad "82" smd rect
			(at 0 73.950068 270)
			(size 1.8034 0.508)
			(layers "B.Cu" "B.Mask" "B.Paste")
			(net "M_F_MA<16>")
		)
		(pad "83" smd rect
			(at 0 74.799952 270)
			(size 1.8034 0.508)
			(layers "B.Cu" "B.Mask" "B.Paste")
			(net "PVDDQ_DEF")
		)
		(pad "84" smd rect
			(at 0 75.65009 270)
			(size 1.8034 0.508)
			(layers "B.Cu" "B.Mask" "B.Paste")
			(net "M_F_CS_N<4>")
		)
		(pad "85" smd rect
			(at 0 76.499974 270)
			(size 1.8034 0.508)
			(layers "B.Cu" "B.Mask" "B.Paste")
			(net "PVDDQ_DEF")
		)
		(pad "86" smd rect
			(at 0 77.350112 270)
			(size 1.8034 0.508)
			(layers "B.Cu" "B.Mask" "B.Paste")
			(net "M_F_MA<15>")
		)
		(pad "87" smd rect
			(at 0 78.199996 270)
			(size 1.8034 0.508)
			(layers "B.Cu" "B.Mask" "B.Paste")
			(net "M_F_ODT<2>")
		)
		(pad "88" smd rect
			(at 0 79.04988 270)
			(size 1.8034 0.508)
			(layers "B.Cu" "B.Mask" "B.Paste")
			(net "PVDDQ_DEF")
		)
		(pad "89" smd rect
			(at 0 79.900018 270)
			(size 1.8034 0.508)
			(layers "B.Cu" "B.Mask" "B.Paste")
			(net "M_F_CS_N<5>")
		)
		(pad "90" smd rect
			(at 0 80.749902 270)
			(size 1.8034 0.508)
			(layers "B.Cu" "B.Mask" "B.Paste")
			(net "PVDDQ_DEF")
		)
		(pad "91" smd rect
			(at 0 81.60004 270)
			(size 1.8034 0.508)
			(layers "B.Cu" "B.Mask" "B.Paste")
			(net "M_F_ODT<3>")
		)
		(pad "92" smd rect
			(at 0 82.449924 270)
			(size 1.8034 0.508)
			(layers "B.Cu" "B.Mask" "B.Paste")
			(net "PVDDQ_DEF")
		)
		(pad "93" smd rect
			(at 0 83.300062 270)
			(size 1.8034 0.508)
			(layers "B.Cu" "B.Mask" "B.Paste")
			(net "M_F_CS_N<6>")
		)
		(pad "94" smd rect
			(at 0 84.149946 270)
			(size 1.8034 0.508)
			(layers "B.Cu" "B.Mask" "B.Paste")
			(net "GND")
		)
		(pad "95" smd rect
			(at 0 85.000084 270)
			(size 1.8034 0.508)
			(layers "B.Cu" "B.Mask" "B.Paste")
			(net "M_F_DQ<36>")
		)
		(pad "96" smd rect
			(at 0 85.849968 270)
			(size 1.8034 0.508)
			(layers "B.Cu" "B.Mask" "B.Paste")
			(net "GND")
		)
		(pad "97" smd rect
			(at 0 86.700106 270)
			(size 1.8034 0.508)
			(layers "B.Cu" "B.Mask" "B.Paste")
			(net "M_F_DQ<32>")
		)
	)
)
